(kicad_pcb
	(version 20260206)
	(generator "pcbnew")
	(generator_version "10.0")
	(general
		(thickness 1.6)
		(legacy_teardrops no)
	)
	(paper "A4")
	(title_block
		(title "03242023_DA0F0TMBIJ0_F0T_Motherboard_J_brd_V01_OCP.brd")
		(comment 1 "Grand Teton / footprints 5240-5245 of 6105")
	)
	(layers
		(0 "F.Cu" signal "TOP")
		(4 "In1.Cu" signal "GND")
		(6 "In2.Cu" signal "IN1")
		(8 "In3.Cu" signal "GND1")
		(10 "In4.Cu" signal "IN2")
		(12 "In5.Cu" signal "GND2")
		(14 "In6.Cu" signal "IN3")
		(16 "In7.Cu" signal "GND3")
		(18 "In8.Cu" signal "VCC")
		(20 "In9.Cu" signal "VCC1")
		(22 "In10.Cu" signal "GND4")
		(24 "In11.Cu" signal "IN4")
		(26 "In12.Cu" signal "GND5")
		(28 "In13.Cu" signal "IN5")
		(30 "In14.Cu" signal "GND6")
		(32 "In15.Cu" signal "IN6")
		(34 "In16.Cu" signal "GND7")
		(2 "B.Cu" signal "BOTTOM")
		(9 "F.Adhes" user "F.Adhesive")
		(11 "B.Adhes" user "B.Adhesive")
		(13 "F.Paste" user "Package Geometry/Pastemask Top")
		(15 "B.Paste" user "Package Geometry/Pastemask Bottom")
		(5 "F.SilkS" user "Ref Des/Silkscreen Top")
		(7 "B.SilkS" user "Ref Des/Silkscreen Bottom")
		(1 "F.Mask" user "Board Geometry/Soldermask Top")
		(3 "B.Mask" user "Board Geometry/Soldermask Bottom")
		(17 "Dwgs.User" user "User.Drawings")
		(19 "Cmts.User" user "User.Comments")
		(21 "Eco1.User" user "User.Eco1")
		(23 "Eco2.User" user "User.Eco2")
		(25 "Edge.Cuts" user "Board Geometry/Outline")
		(27 "Margin" user)
		(31 "F.CrtYd" user "Package Geometry/Place Bound Top")
		(29 "B.CrtYd" user "Package Geometry/Place Bound Bottom")
		(35 "F.Fab" user "Ref Des/Assembly Top")
		(33 "B.Fab" user "Ref Des/Assembly Bottom")
	)
	(footprint ""
		(layer "B.Cu")
		(at 200.661778 -109.86897 180)
		(property "Reference" "R126"
			(at 0 0 0)
			(layer "B.SilkS")
			(hide yes)
			(effects
				(font
					(size 1.27 1.27)
				)
				(justify mirror)
			)
		)
		(property "Value" ""
			(at 0 0 0)
			(layer "B.Fab")
			(effects
				(font
					(size 1.27 1.27)
				)
				(justify mirror)
			)
		)
		(duplicate_pad_numbers_are_jumpers no)
		(fp_line
			(start 0.7874 0.4064)
			(end 0.7874 -0.4064)
			(stroke
				(width 0.1524)
				(type default)
			)
			(layer "B.SilkS")
		)
		(fp_line
			(start 0.7874 -0.4064)
			(end -0.7874 -0.4064)
			(stroke
				(width 0.1524)
				(type default)
			)
			(layer "B.SilkS")
		)
		(fp_line
			(start -0.7874 0.4064)
			(end 0.7874 0.4064)
			(stroke
				(width 0.1524)
				(type default)
			)
			(layer "B.SilkS")
		)
		(fp_line
			(start -0.7874 -0.4064)
			(end -0.7874 0.4064)
			(stroke
				(width 0.1524)
				(type default)
			)
			(layer "B.SilkS")
		)
		(fp_line
			(start 0.67945 0.3048)
			(end 0.67945 -0.305054)
			(stroke
				(width 0.1)
				(type default)
			)
			(layer "B.Fab")
		)
		(fp_line
			(start 0.67945 -0.305054)
			(end 0.12065 -0.305054)
			(stroke
				(width 0.1)
				(type default)
			)
			(layer "B.Fab")
		)
		(fp_line
			(start 0.12065 0.3048)
			(end 0.67945 0.3048)
			(stroke
				(width 0.1)
				(type default)
			)
			(layer "B.Fab")
		)
		(fp_line
			(start 0.12065 0.2794)
			(end 0.12065 0.3048)
			(stroke
				(width 0.1)
				(type default)
			)
			(layer "B.Fab")
		)
		(fp_line
			(start 0.12065 -0.2794)
			(end -0.12065 -0.2794)
			(stroke
				(width 0.1)
				(type default)
			)
			(layer "B.Fab")
		)
		(fp_line
			(start 0.12065 -0.305054)
			(end 0.12065 -0.2794)
			(stroke
				(width 0.1)
				(type default)
			)
			(layer "B.Fab")
		)
		(fp_line
			(start -0.120396 0.3048)
			(end -0.120396 0.2794)
			(stroke
				(width 0.1)
				(type default)
			)
			(layer "B.Fab")
		)
		(fp_line
			(start -0.120396 0.2794)
			(end 0.12065 0.2794)
			(stroke
				(width 0.1)
				(type default)
			)
			(layer "B.Fab")
		)
		(fp_line
			(start -0.12065 -0.2794)
			(end -0.12065 -0.3048)
			(stroke
				(width 0.1)
				(type default)
			)
			(layer "B.Fab")
		)
		(fp_line
			(start -0.12065 -0.3048)
			(end -0.67945 -0.3048)
			(stroke
				(width 0.1)
				(type default)
			)
			(layer "B.Fab")
		)
		(fp_line
			(start -0.67945 0.3048)
			(end -0.120396 0.3048)
			(stroke
				(width 0.1)
				(type default)
			)
			(layer "B.Fab")
		)
		(fp_line
			(start -0.67945 -0.3048)
			(end -0.67945 0.3048)
			(stroke
				(width 0.1)
				(type default)
			)
			(layer "B.Fab")
		)
		(pad "1" smd circle
			(at 0.40005 0)
			(size 0 0)
			(layers "B.Cu" "B.Mask" "B.Paste")
			(net "PWRGD_DRAMPWRGD_CPU1_EF_R_LVC1")
		)
		(pad "2" smd circle
			(at -0.40005 0)
			(size 0 0)
			(layers "B.Cu" "B.Mask" "B.Paste")
			(net "PWRGD_DRAMPWRGD_CPU1_EF_LVC1_R2")
		)
	)
	(footprint ""
		(layer "B.Cu")
		(at 63.718186 -15.772384 90)
		(property "Reference" "R3208"
			(at 0 0 90)
			(layer "B.SilkS")
			(hide yes)
			(effects
				(font
					(size 1.27 1.27)
				)
				(justify mirror)
			)
		)
		(property "Value" ""
			(at 0 0 90)
			(layer "B.Fab")
			(effects
				(font
					(size 1.27 1.27)
				)
				(justify mirror)
			)
		)
		(duplicate_pad_numbers_are_jumpers no)
		(fp_line
			(start 0.7874 -0.4064)
			(end -0.7874 -0.4064)
			(stroke
				(width 0.1524)
				(type default)
			)
			(layer "B.SilkS")
		)
		(fp_line
			(start -0.7874 -0.4064)
			(end -0.7874 0.4064)
			(stroke
				(width 0.1524)
				(type default)
			)
			(layer "B.SilkS")
		)
		(fp_line
			(start 0.7874 0.4064)
			(end 0.7874 -0.4064)
			(stroke
				(width 0.1524)
				(type default)
			)
			(layer "B.SilkS")
		)
		(fp_line
			(start -0.7874 0.4064)
			(end 0.7874 0.4064)
			(stroke
				(width 0.1524)
				(type default)
			)
			(layer "B.SilkS")
		)
		(fp_line
			(start 0.67945 -0.305054)
			(end 0.12065 -0.305054)
			(stroke
				(width 0.1)
				(type default)
			)
			(layer "B.Fab")
		)
		(fp_line
			(start 0.12065 -0.305054)
			(end 0.12065 -0.2794)
			(stroke
				(width 0.1)
				(type default)
			)
			(layer "B.Fab")
		)
		(fp_line
			(start -0.12065 -0.3048)
			(end -0.67945 -0.3048)
			(stroke
				(width 0.1)
				(type default)
			)
			(layer "B.Fab")
		)
		(fp_line
			(start -0.67945 -0.3048)
			(end -0.67945 0.3048)
			(stroke
				(width 0.1)
				(type default)
			)
			(layer "B.Fab")
		)
		(fp_line
			(start 0.12065 -0.2794)
			(end -0.12065 -0.2794)
			(stroke
				(width 0.1)
				(type default)
			)
			(layer "B.Fab")
		)
		(fp_line
			(start -0.12065 -0.2794)
			(end -0.12065 -0.3048)
			(stroke
				(width 0.1)
				(type default)
			)
			(layer "B.Fab")
		)
		(fp_line
			(start 0.12065 0.2794)
			(end 0.12065 0.3048)
			(stroke
				(width 0.1)
				(type default)
			)
			(layer "B.Fab")
		)
		(fp_line
			(start -0.120396 0.2794)
			(end 0.12065 0.2794)
			(stroke
				(width 0.1)
				(type default)
			)
			(layer "B.Fab")
		)
		(fp_line
			(start 0.67945 0.3048)
			(end 0.67945 -0.305054)
			(stroke
				(width 0.1)
				(type default)
			)
			(layer "B.Fab")
		)
		(fp_line
			(start 0.12065 0.3048)
			(end 0.67945 0.3048)
			(stroke
				(width 0.1)
				(type default)
			)
			(layer "B.Fab")
		)
		(fp_line
			(start -0.120396 0.3048)
			(end -0.120396 0.2794)
			(stroke
				(width 0.1)
				(type default)
			)
			(layer "B.Fab")
		)
		(fp_line
			(start -0.67945 0.3048)
			(end -0.120396 0.3048)
			(stroke
				(width 0.1)
				(type default)
			)
			(layer "B.Fab")
		)
		(pad "1" smd circle
			(at 0.40005 0 270)
			(size 0 0)
			(layers "B.Cu" "B.Mask" "B.Paste")
			(net "OCP_V3_2_ISO_BIF0_EN")
		)
		(pad "2" smd circle
			(at -0.40005 0 270)
			(size 0 0)
			(layers "B.Cu" "B.Mask" "B.Paste")
			(net "GND")
		)
	)
	(footprint ""
		(layer "B.Cu")
		(at 318.223138 -189.73673 90)
		(property "Reference" "R243"
			(at 0 0 90)
			(layer "B.SilkS")
			(hide yes)
			(effects
				(font
					(size 1.27 1.27)
				)
				(justify mirror)
			)
		)
		(property "Value" ""
			(at 0 0 90)
			(layer "B.Fab")
			(effects
				(font
					(size 1.27 1.27)
				)
				(justify mirror)
			)
		)
		(duplicate_pad_numbers_are_jumpers no)
		(fp_line
			(start 0.7874 -0.4064)
			(end -0.7874 -0.4064)
			(stroke
				(width 0.1524)
				(type default)
			)
			(layer "B.SilkS")
		)
		(fp_line
			(start -0.7874 -0.4064)
			(end -0.7874 0.4064)
			(stroke
				(width 0.1524)
				(type default)
			)
			(layer "B.SilkS")
		)
		(fp_line
			(start 0.7874 0.4064)
			(end 0.7874 -0.4064)
			(stroke
				(width 0.1524)
				(type default)
			)
			(layer "B.SilkS")
		)
		(fp_line
			(start -0.7874 0.4064)
			(end 0.7874 0.4064)
			(stroke
				(width 0.1524)
				(type default)
			)
			(layer "B.SilkS")
		)
		(fp_line
			(start 0.67945 -0.305054)
			(end 0.12065 -0.305054)
			(stroke
				(width 0.1)
				(type default)
			)
			(layer "B.Fab")
		)
		(fp_line
			(start 0.12065 -0.305054)
			(end 0.12065 -0.2794)
			(stroke
				(width 0.1)
				(type default)
			)
			(layer "B.Fab")
		)
		(fp_line
			(start -0.12065 -0.3048)
			(end -0.67945 -0.3048)
			(stroke
				(width 0.1)
				(type default)
			)
			(layer "B.Fab")
		)
		(fp_line
			(start -0.67945 -0.3048)
			(end -0.67945 0.3048)
			(stroke
				(width 0.1)
				(type default)
			)
			(layer "B.Fab")
		)
		(fp_line
			(start 0.12065 -0.2794)
			(end -0.12065 -0.2794)
			(stroke
				(width 0.1)
				(type default)
			)
			(layer "B.Fab")
		)
		(fp_line
			(start -0.12065 -0.2794)
			(end -0.12065 -0.3048)
			(stroke
				(width 0.1)
				(type default)
			)
			(layer "B.Fab")
		)
		(fp_line
			(start 0.12065 0.2794)
			(end 0.12065 0.3048)
			(stroke
				(width 0.1)
				(type default)
			)
			(layer "B.Fab")
		)
		(fp_line
			(start -0.120396 0.2794)
			(end 0.12065 0.2794)
			(stroke
				(width 0.1)
				(type default)
			)
			(layer "B.Fab")
		)
		(fp_line
			(start 0.67945 0.3048)
			(end 0.67945 -0.305054)
			(stroke
				(width 0.1)
				(type default)
			)
			(layer "B.Fab")
		)
		(fp_line
			(start 0.12065 0.3048)
			(end 0.67945 0.3048)
			(stroke
				(width 0.1)
				(type default)
			)
			(layer "B.Fab")
		)
		(fp_line
			(start -0.120396 0.3048)
			(end -0.120396 0.2794)
			(stroke
				(width 0.1)
				(type default)
			)
			(layer "B.Fab")
		)
		(fp_line
			(start -0.67945 0.3048)
			(end -0.120396 0.3048)
			(stroke
				(width 0.1)
				(type default)
			)
			(layer "B.Fab")
		)
		(pad "1" smd circle
			(at 0.40005 0 270)
			(size 0 0)
			(layers "B.Cu" "B.Mask" "B.Paste")
			(net "PVNN_TERM_CPU0")
		)
		(pad "2" smd circle
			(at -0.40005 0 270)
			(size 0 0)
			(layers "B.Cu" "B.Mask" "B.Paste")
			(net "H_CPU0_PROCHOT_LVC1_N")
		)
	)
	(footprint ""
		(layer "B.Cu")
		(at 252.242574 -101.754178 180)
		(property "Reference" "C114"
			(at 0 0 0)
			(layer "B.SilkS")
			(hide yes)
			(effects
				(font
					(size 1.27 1.27)
				)
				(justify mirror)
			)
		)
		(property "Value" ""
			(at 0 0 0)
			(layer "B.Fab")
			(effects
				(font
					(size 1.27 1.27)
				)
				(justify mirror)
			)
		)
		(duplicate_pad_numbers_are_jumpers no)
		(fp_line
			(start 0.7874 0.4064)
			(end 0.7874 -0.4064)
			(stroke
				(width 0.1524)
				(type default)
			)
			(layer "B.SilkS")
		)
		(fp_line
			(start 0.7874 -0.4064)
			(end -0.7874 -0.4064)
			(stroke
				(width 0.1524)
				(type default)
			)
			(layer "B.SilkS")
		)
		(fp_line
			(start -0.7874 0.4064)
			(end 0.7874 0.4064)
			(stroke
				(width 0.1524)
				(type default)
			)
			(layer "B.SilkS")
		)
		(fp_line
			(start -0.7874 -0.4064)
			(end -0.7874 0.4064)
			(stroke
				(width 0.1524)
				(type default)
			)
			(layer "B.SilkS")
		)
		(fp_line
			(start 0.67945 0.3048)
			(end 0.67945 -0.305054)
			(stroke
				(width 0.1)
				(type default)
			)
			(layer "B.Fab")
		)
		(fp_line
			(start 0.67945 -0.305054)
			(end 0.12065 -0.305054)
			(stroke
				(width 0.1)
				(type default)
			)
			(layer "B.Fab")
		)
		(fp_line
			(start 0.12065 0.3048)
			(end 0.67945 0.3048)
			(stroke
				(width 0.1)
				(type default)
			)
			(layer "B.Fab")
		)
		(fp_line
			(start 0.12065 0.2794)
			(end 0.12065 0.3048)
			(stroke
				(width 0.1)
				(type default)
			)
			(layer "B.Fab")
		)
		(fp_line
			(start 0.12065 -0.2794)
			(end -0.12065 -0.2794)
			(stroke
				(width 0.1)
				(type default)
			)
			(layer "B.Fab")
		)
		(fp_line
			(start 0.12065 -0.305054)
			(end 0.12065 -0.2794)
			(stroke
				(width 0.1)
				(type default)
			)
			(layer "B.Fab")
		)
		(fp_line
			(start -0.120396 0.3048)
			(end -0.120396 0.2794)
			(stroke
				(width 0.1)
				(type default)
			)
			(layer "B.Fab")
		)
		(fp_line
			(start -0.120396 0.2794)
			(end 0.12065 0.2794)
			(stroke
				(width 0.1)
				(type default)
			)
			(layer "B.Fab")
		)
		(fp_line
			(start -0.12065 -0.2794)
			(end -0.12065 -0.3048)
			(stroke
				(width 0.1)
				(type default)
			)
			(layer "B.Fab")
		)
		(fp_line
			(start -0.12065 -0.3048)
			(end -0.67945 -0.3048)
			(stroke
				(width 0.1)
				(type default)
			)
			(layer "B.Fab")
		)
		(fp_line
			(start -0.67945 0.3048)
			(end -0.120396 0.3048)
			(stroke
				(width 0.1)
				(type default)
			)
			(layer "B.Fab")
		)
		(fp_line
			(start -0.67945 -0.3048)
			(end -0.67945 0.3048)
			(stroke
				(width 0.1)
				(type default)
			)
			(layer "B.Fab")
		)
		(pad "1" smd circle
			(at 0.40005 0)
			(size 0 0)
			(layers "B.Cu" "B.Mask" "B.Paste")
			(net "P3V3_AUX_CLK_GEN_VDDA25M_CK440")
		)
		(pad "2" smd circle
			(at -0.40005 0)
			(size 0 0)
			(layers "B.Cu" "B.Mask" "B.Paste")
			(net "GND")
		)
	)
	(footprint ""
		(layer "B.Cu")
		(at 307.363622 -30.724348)
		(property "Reference" "R379"
			(at 0 0 0)
			(layer "B.SilkS")
			(hide yes)
			(effects
				(font
					(size 1.27 1.27)
				)
				(justify mirror)
			)
		)
		(property "Value" ""
			(at 0 0 0)
			(layer "B.Fab")
			(effects
				(font
					(size 1.27 1.27)
				)
				(justify mirror)
			)
		)
		(duplicate_pad_numbers_are_jumpers no)
		(fp_line
			(start -0.7874 -0.4064)
			(end -0.7874 0.4064)
			(stroke
				(width 0.1524)
				(type default)
			)
			(layer "B.SilkS")
		)
		(fp_line
			(start -0.7874 0.4064)
			(end 0.7874 0.4064)
			(stroke
				(width 0.1524)
				(type default)
			)
			(layer "B.SilkS")
		)
		(fp_line
			(start 0.7874 -0.4064)
			(end -0.7874 -0.4064)
			(stroke
				(width 0.1524)
				(type default)
			)
			(layer "B.SilkS")
		)
		(fp_line
			(start 0.7874 0.4064)
			(end 0.7874 -0.4064)
			(stroke
				(width 0.1524)
				(type default)
			)
			(layer "B.SilkS")
		)
		(fp_line
			(start -0.67945 -0.3048)
			(end -0.67945 0.3048)
			(stroke
				(width 0.1)
				(type default)
			)
			(layer "B.Fab")
		)
		(fp_line
			(start -0.67945 0.3048)
			(end -0.120396 0.3048)
			(stroke
				(width 0.1)
				(type default)
			)
			(layer "B.Fab")
		)
		(fp_line
			(start -0.12065 -0.3048)
			(end -0.67945 -0.3048)
			(stroke
				(width 0.1)
				(type default)
			)
			(layer "B.Fab")
		)
		(fp_line
			(start -0.12065 -0.2794)
			(end -0.12065 -0.3048)
			(stroke
				(width 0.1)
				(type default)
			)
			(layer "B.Fab")
		)
		(fp_line
			(start -0.120396 0.2794)
			(end 0.12065 0.2794)
			(stroke
				(width 0.1)
				(type default)
			)
			(layer "B.Fab")
		)
		(fp_line
			(start -0.120396 0.3048)
			(end -0.120396 0.2794)
			(stroke
				(width 0.1)
				(type default)
			)
			(layer "B.Fab")
		)
		(fp_line
			(start 0.12065 -0.305054)
			(end 0.12065 -0.2794)
			(stroke
				(width 0.1)
				(type default)
			)
			(layer "B.Fab")
		)
		(fp_line
			(start 0.12065 -0.2794)
			(end -0.12065 -0.2794)
			(stroke
				(width 0.1)
				(type default)
			)
			(layer "B.Fab")
		)
		(fp_line
			(start 0.12065 0.2794)
			(end 0.12065 0.3048)
			(stroke
				(width 0.1)
				(type default)
			)
			(layer "B.Fab")
		)
		(fp_line
			(start 0.12065 0.3048)
			(end 0.67945 0.3048)
			(stroke
				(width 0.1)
				(type default)
			)
			(layer "B.Fab")
		)
		(fp_line
			(start 0.67945 -0.305054)
			(end 0.12065 -0.305054)
			(stroke
				(width 0.1)
				(type default)
			)
			(layer "B.Fab")
		)
		(fp_line
			(start 0.67945 0.3048)
			(end 0.67945 -0.305054)
			(stroke
				(width 0.1)
				(type default)
			)
			(layer "B.Fab")
		)
		(pad "1" smd circle
			(at 0.40005 0 180)
			(size 0 0)
			(layers "B.Cu" "B.Mask" "B.Paste")
			(net "FM_ADR_MODE1")
		)
		(pad "2" smd circle
			(at -0.40005 0 180)
			(size 0 0)
			(layers "B.Cu" "B.Mask" "B.Paste")
			(net "GND")
		)
	)
	(footprint ""
		(layer "B.Cu")
		(at 92.973398 -355.03231 90)
		(property "Reference" "PR2556"
			(at 0 0 90)
			(layer "B.SilkS")
			(hide yes)
			(effects
				(font
					(size 1.27 1.27)
				)
				(justify mirror)
			)
		)
		(property "Value" ""
			(at 0 0 90)
			(layer "B.Fab")
			(effects
				(font
					(size 1.27 1.27)
				)
				(justify mirror)
			)
		)
		(duplicate_pad_numbers_are_jumpers no)
		(fp_line
			(start 4.0386 -1.7526)
			(end -4.0386 -1.7526)
			(stroke
				(width 0.1524)
				(type default)
			)
			(layer "B.SilkS")
		)
		(fp_line
			(start -4.0386 -1.7526)
			(end -4.0386 1.7526)
			(stroke
				(width 0.1524)
				(type default)
			)
			(layer "B.SilkS")
		)
		(fp_line
			(start 4.0386 1.7526)
			(end 4.0386 -1.7526)
			(stroke
				(width 0.1524)
				(type default)
			)
			(layer "B.SilkS")
		)
		(fp_line
			(start -4.0386 1.7526)
			(end 4.0386 1.7526)
			(stroke
				(width 0.1524)
				(type default)
			)
			(layer "B.SilkS")
		)
		(fp_line
			(start 4.0386 -1.7526)
			(end -4.0386 -1.7526)
			(stroke
				(width 0.1)
				(type default)
			)
			(layer "B.Fab")
		)
		(fp_line
			(start -4.0386 -1.7526)
			(end -4.0386 1.7526)
			(stroke
				(width 0.1)
				(type default)
			)
			(layer "B.Fab")
		)
		(fp_line
			(start 4.0386 1.7526)
			(end 4.0386 -1.7526)
			(stroke
				(width 0.1)
				(type default)
			)
			(layer "B.Fab")
		)
		(fp_line
			(start -4.0386 1.7526)
			(end 4.0386 1.7526)
			(stroke
				(width 0.1)
				(type default)
			)
			(layer "B.Fab")
		)
		(pad "1" smd rect
			(at 3.1115 0 270)
			(size 1.524 3.2004)
			(layers "B.Cu" "B.Mask" "B.Paste")
			(net "P12V_AUX")
		)
		(pad "2" smd rect
			(at -3.1115 0 270)
			(size 1.524 3.2004)
			(layers "B.Cu" "B.Mask" "B.Paste")
			(net "SW_P12V_PVCCIN_CPU1_FLT")
		)
	)
)
